# BASEBOARD_FAB2 (Tioga Pass) — schematic netlist excerpt (pin names and nets, part order shuffled) for the footprints in the layout excerpt that follows; sources: Cadence DE-HDL packaged netlist, KiCad conversion of Wiwynn_Tioga_Pass_MB.brd

C2D29  CAP_A  22.0UF 4V 20% X6S  pkg 0603V  page 76 : A = PVCCMCP_CPU1 ; B = GND
R8A7  RES  100.0K 1% EMPTY  pkg 0402  page 235 : A = P3V3_STBY ; B = VR_PVNN_PCH_VREN
C4D48  CAP  1.0UF 16V 10% X6S  pkg 0402  page 202 : A = VR_FET_SW_P12V_STBY_PVCCIN_CPU0 ; B = GND

(kicad_pcb
	(version 20260206)
	(generator "pcbnew")
	(generator_version "10.0")
	(general
		(thickness 1.6)
		(legacy_teardrops no)
	)
	(paper "A4")
	(title_block
		(title "Wiwynn_Tioga_Pass_MB.brd")
		(comment 1 "Tioga Pass / footprints 417-419 of 4770")
	)
	(layers
		(0 "F.Cu" signal "TOP")
		(4 "In1.Cu" signal "L2GND")
		(6 "In2.Cu" signal "L3")
		(8 "In3.Cu" signal "L4GND")
		(10 "In4.Cu" signal "L5")
		(12 "In5.Cu" signal "L6GND")
		(14 "In6.Cu" signal "L7VCC")
		(16 "In7.Cu" signal "L8VCC")
		(18 "In8.Cu" signal "L9GND")
		(20 "In9.Cu" signal "L10")
		(22 "In10.Cu" signal "L11GND")
		(24 "In11.Cu" signal "L12")
		(26 "In12.Cu" signal "L13GND")
		(2 "B.Cu" signal "BOTTOM")
		(9 "F.Adhes" user "F.Adhesive")
		(11 "B.Adhes" user "B.Adhesive")
		(13 "F.Paste" user "Package Geometry/Pastemask Top")
		(15 "B.Paste" user "Package Geometry/Pastemask Bottom")
		(5 "F.SilkS" user "Ref Des/Silkscreen Top")
		(7 "B.SilkS" user "Ref Des/Silkscreen Bottom")
		(1 "F.Mask" user "Board Geometry/Soldermask Top")
		(3 "B.Mask" user "Board Geometry/Soldermask Bottom")
		(17 "Dwgs.User" user "User.Drawings")
		(19 "Cmts.User" user "User.Comments")
		(21 "Eco1.User" user "User.Eco1")
		(23 "Eco2.User" user "User.Eco2")
		(25 "Edge.Cuts" user "Board Geometry/Outline")
		(27 "Margin" user)
		(31 "F.CrtYd" user "Package Geometry/Place Bound Top")
		(29 "B.CrtYd" user "Package Geometry/Place Bound Bottom")
		(35 "F.Fab" user "Ref Des/Assembly Top")
		(33 "B.Fab" user "Ref Des/Assembly Bottom")
	)
	(footprint ""
		(layer "F.Cu")
		(at 399.923 -149.225 180)
		(property "Reference" "R8A7"
			(at 0 0 180)
			(layer "F.SilkS")
			(hide yes)
			(effects
				(font
					(size 1.27 1.27)
				)
			)
		)
		(property "Value" ""
			(at 0 0 180)
			(layer "F.Fab")
			(effects
				(font
					(size 1.27 1.27)
				)
			)
		)
		(duplicate_pad_numbers_are_jumpers no)
		(fp_poly
			(pts
				(xy -0.2794 -0.1016) (xy 0.2794 -0.1016) (xy 0.2794 0.9906) (xy -0.2794 0.9906)
			)
			(stroke
				(width 0)
				(type default)
			)
			(fill no)
			(layer "F.CrtYd")
		)
		(fp_line
			(start 0.2794 0.9906)
			(end 0.2794 -0.1016)
			(stroke
				(width 0.1)
				(type default)
			)
			(layer "F.Fab")
		)
		(fp_line
			(start 0.2794 -0.1016)
			(end -0.2794 -0.1016)
			(stroke
				(width 0.1)
				(type default)
			)
			(layer "F.Fab")
		)
		(fp_line
			(start -0.2794 0.9906)
			(end 0.2794 0.9906)
			(stroke
				(width 0.1)
				(type default)
			)
			(layer "F.Fab")
		)
		(fp_line
			(start -0.2794 -0.1016)
			(end -0.2794 0.9906)
			(stroke
				(width 0.1)
				(type default)
			)
			(layer "F.Fab")
		)
		(pad "1" smd rect
			(at 0 0 180)
			(size 0.508 0.508)
			(layers "F.Cu" "F.Mask" "F.Paste")
			(net "P3V3_STBY")
		)
		(pad "2" smd rect
			(at 0 0.889 180)
			(size 0.508 0.508)
			(layers "F.Cu" "F.Mask" "F.Paste")
			(net "VR_PVNN_PCH_VREN")
		)
		(zone
			(layer "F.Cu")
			(hatch none 0.5)
			(connect_pads
				(clearance 0)
			)
			(min_thickness 0.25)
			(keepout
				(tracks not_allowed)
				(vias allowed)
				(pads allowed)
				(copperpour not_allowed)
				(footprints allowed)
			)
			(placement
				(enabled no)
				(sheetname "")
			)
			(fill
				(thermal_gap 0.5)
				(thermal_bridge_width 0.5)
				(island_removal_mode 0)
			)
			(polygon
				(pts
					(xy 400.177 -149.86) (xy 399.669 -149.86) (xy 399.669 -149.479) (xy 400.177 -149.479)
				)
			)
		)
		(zone
			(layer "F.Cu")
			(hatch none 0.5)
			(connect_pads
				(clearance 0)
			)
			(min_thickness 0.25)
			(keepout
				(tracks allowed)
				(vias not_allowed)
				(pads allowed)
				(copperpour not_allowed)
				(footprints allowed)
			)
			(placement
				(enabled no)
				(sheetname "")
			)
			(fill
				(thermal_gap 0.5)
				(thermal_bridge_width 0.5)
				(island_removal_mode 0)
			)
			(polygon
				(pts
					(xy 400.177 -149.479) (xy 399.669 -149.479) (xy 399.669 -149.86) (xy 400.177 -149.86)
				)
			)
		)
	)
	(footprint ""
		(layer "F.Cu")
		(at 105.65384 -77.636116)
		(property "Reference" "C2D29"
			(at 0 0 0)
			(layer "F.SilkS")
			(hide yes)
			(effects
				(font
					(size 1.27 1.27)
				)
			)
		)
		(property "Value" ""
			(at 0 0 0)
			(layer "F.Fab")
			(effects
				(font
					(size 1.27 1.27)
				)
			)
		)
		(duplicate_pad_numbers_are_jumpers no)
		(fp_poly
			(pts
				(xy -0.4953 -0.2032) (xy 0.4953 -0.2032) (xy 0.4953 1.6002) (xy -0.4953 1.6002)
			)
			(stroke
				(width 0)
				(type default)
			)
			(fill no)
			(layer "F.CrtYd")
		)
		(fp_line
			(start -0.4953 -0.2032)
			(end 0.4953 -0.2032)
			(stroke
				(width 0.1)
				(type default)
			)
			(layer "F.Fab")
		)
		(fp_line
			(start -0.4953 1.6002)
			(end -0.4953 -0.2032)
			(stroke
				(width 0.1)
				(type default)
			)
			(layer "F.Fab")
		)
		(fp_line
			(start 0.4953 -0.2032)
			(end 0.4953 1.6002)
			(stroke
				(width 0.1)
				(type default)
			)
			(layer "F.Fab")
		)
		(fp_line
			(start 0.4953 1.6002)
			(end -0.4953 1.6002)
			(stroke
				(width 0.1)
				(type default)
			)
			(layer "F.Fab")
		)
		(pad "1" smd rect
			(at 0 0)
			(size 0.762 0.889)
			(layers "F.Cu" "F.Mask" "F.Paste")
			(net "PVCCMCP_CPU1")
		)
		(pad "2" smd rect
			(at 0 1.397)
			(size 0.762 0.889)
			(layers "F.Cu" "F.Mask" "F.Paste")
			(net "GND")
		)
		(zone
			(layer "F.Cu")
			(hatch none 0.5)
			(connect_pads
				(clearance 0)
			)
			(min_thickness 0.25)
			(keepout
				(tracks not_allowed)
				(vias allowed)
				(pads allowed)
				(copperpour not_allowed)
				(footprints allowed)
			)
			(placement
				(enabled no)
				(sheetname "")
			)
			(fill
				(thermal_gap 0.5)
				(thermal_bridge_width 0.5)
				(island_removal_mode 0)
			)
			(polygon
				(pts
					(xy 105.27284 -77.191616) (xy 106.03484 -77.191616) (xy 106.03484 -76.683616) (xy 105.27284 -76.683616)
				)
			)
		)
	)
	(footprint ""
		(layer "F.Cu")
		(at 194.749928 -67.97294 -90)
		(property "Reference" "C4D48"
			(at 0 0 270)
			(layer "F.SilkS")
			(hide yes)
			(effects
				(font
					(size 1.27 1.27)
				)
			)
		)
		(property "Value" ""
			(at 0 0 270)
			(layer "F.Fab")
			(effects
				(font
					(size 1.27 1.27)
				)
			)
		)
		(duplicate_pad_numbers_are_jumpers no)
		(fp_poly
			(pts
				(xy 0.3048 -0.1016) (xy 0.3048 0.9906) (xy -0.3048 0.9906) (xy -0.3048 -0.1016)
			)
			(stroke
				(width 0)
				(type default)
			)
			(fill no)
			(layer "F.CrtYd")
		)
		(fp_line
			(start -0.3048 0.9906)
			(end 0.3048 0.9906)
			(stroke
				(width 0.1)
				(type default)
			)
			(layer "F.Fab")
		)
		(fp_line
			(start 0.3048 0.9906)
			(end 0.3048 -0.1016)
			(stroke
				(width 0.1)
				(type default)
			)
			(layer "F.Fab")
		)
		(fp_line
			(start -0.3048 -0.1016)
			(end -0.3048 0.9906)
			(stroke
				(width 0.1)
				(type default)
			)
			(layer "F.Fab")
		)
		(fp_line
			(start 0.3048 -0.1016)
			(end -0.3048 -0.1016)
			(stroke
				(width 0.1)
				(type default)
			)
			(layer "F.Fab")
		)
		(pad "1" smd rect
			(at 0 0 270)
			(size 0.508 0.508)
			(layers "F.Cu" "F.Mask" "F.Paste")
			(net "VR_FET_SW_P12V_STBY_PVCCIN_CPU0")
		)
		(pad "2" smd rect
			(at 0 0.889 270)
			(size 0.508 0.508)
			(layers "F.Cu" "F.Mask" "F.Paste")
			(net "GND")
		)
		(zone
			(layer "F.Cu")
			(hatch none 0.5)
			(connect_pads
				(clearance 0)
			)
			(min_thickness 0.25)
			(keepout
				(tracks not_allowed)
				(vias allowed)
				(pads allowed)
				(copperpour not_allowed)
				(footprints allowed)
			)
			(placement
				(enabled no)
				(sheetname "")
			)
			(fill
				(thermal_gap 0.5)
				(thermal_bridge_width 0.5)
				(island_removal_mode 0)
			)
			(polygon
				(pts
					(xy 194.114928 -68.22694) (xy 194.114928 -67.71894) (xy 194.495928 -67.71894) (xy 194.495928 -68.22694)
				)
			)
		)
		(zone
			(layer "F.Cu")
			(hatch none 0.5)
			(connect_pads
				(clearance 0)
			)
			(min_thickness 0.25)
			(keepout
				(tracks allowed)
				(vias not_allowed)
				(pads allowed)
				(copperpour not_allowed)
				(footprints allowed)
			)
			(placement
				(enabled no)
				(sheetname "")
			)
			(fill
				(thermal_gap 0.5)
				(thermal_bridge_width 0.5)
				(island_removal_mode 0)
			)
			(polygon
				(pts
					(xy 194.495928 -68.22694) (xy 194.495928 -67.71894) (xy 194.114928 -67.71894) (xy 194.114928 -68.22694)
				)
			)
		)
	)
)
